(kicad_pcb
	(version 20221018)
	(generator pcbnew)
	(general
    (thickness 1.62)
  )
	(paper "A4")
	(title_block
    (title "ECP5 - Datacenter Secure Control Module (DC-SCM)")
    (date "2024-07-01")
    (rev "1.2.1")
		(comment 9 "footprints 207-209 of 506")
	)
	(layers
    (0 "F.Cu" signal)
    (1 "In1.Cu" power)
    (2 "In2.Cu" signal)
    (3 "In3.Cu" power)
    (4 "In4.Cu" power)
    (5 "In5.Cu" signal)
    (6 "In6.Cu" power)
    (31 "B.Cu" signal)
    (32 "B.Adhes" user "B.Adhesive")
    (33 "F.Adhes" user "F.Adhesive")
    (34 "B.Paste" user)
    (35 "F.Paste" user)
    (36 "B.SilkS" user "B.Silkscreen")
    (37 "F.SilkS" user "F.Silkscreen")
    (38 "B.Mask" user)
    (39 "F.Mask" user)
    (40 "Dwgs.User" user "User.Drawings")
    (41 "Cmts.User" user "User.Comments")
    (42 "Eco1.User" user "User.Eco1")
    (43 "Eco2.User" user "User.Eco2")
    (44 "Edge.Cuts" user)
    (45 "Margin" user)
    (46 "B.CrtYd" user "B.Courtyard")
    (47 "F.CrtYd" user "F.Courtyard")
    (48 "B.Fab" user)
    (49 "F.Fab" user)
  )
	(footprint "antmicro-footprints:PinSocket_2x6_P2.54mm_Drill1.02mm_PMOD" (layer "F.Cu")
    (at 64.6 100.755 90)
    (descr "http://portal.fciconnect.com/Comergent//fci/drawing/68020.pdf")
    (property "Author" "Antmicro")
    (property "License" "Apache-2.0")
    (property "MPN" "M20-7830642")
    (property "Manufacturer" "Harwin")
    (property "Sheetfile" "rot.kicad_sch")
    (property "Sheetname" "RoT")
    (property "ki_description" "PCB Receptacle, Board-to-Board, 2.54 mm, 2 Rows, 12 Contacts, Through Hole Mount, M20")
    (property "ki_keywords" "CONNECTOR, HEADER")
    (attr through_hole)
    (fp_text reference "J4" (at 4.42 0.06 180) (layer "F.SilkS")
        (effects (font (size 0.7 0.7) (thickness 0.15)) (justify left bottom))
    )
    (fp_text value "PinSocket_2x6_P2.54mm_Drill1.02mm_PMOD" (at 1.6 15.8 90) (layer "F.Fab")
        (effects (font (size 0.7 0.7) (thickness 0.15)) (justify left bottom))
    )
    (fp_text user "${REFERENCE}" (at -1.52 17.8 90) (layer "F.Fab") hide
        (effects (font (size 0.7 0.7) (thickness 0.15)) (justify left bottom))
    )
    (fp_text user "License: Apache-2.0" (at -1.52 20.199 90) (layer "F.Fab") hide
        (effects (font (size 0.7 0.7) (thickness 0.15)) (justify left bottom))
    )
    (fp_text user "Author: Antmicro" (at -1.52 18.998 90) (layer "F.Fab") hide
        (effects (font (size 0.7 0.7) (thickness 0.15)) (justify left bottom))
    )
    (fp_line (start -1.401 -1.401) (end -1.401 -1)
      (stroke (width 0.15) (type solid)) (layer "F.SilkS"))
    (fp_line (start -1.401 -1.401) (end -1 -1.401)
      (stroke (width 0.15) (type solid)) (layer "F.SilkS"))
    (fp_line (start -1.401 14.098) (end -1.401 13.698)
      (stroke (width 0.15) (type solid)) (layer "F.SilkS"))
    (fp_line (start -1.401 14.098) (end -1 14.098)
      (stroke (width 0.15) (type solid)) (layer "F.SilkS"))
    (fp_line (start 3.898 -1.401) (end 3.499 -1.401)
      (stroke (width 0.15) (type solid)) (layer "F.SilkS"))
    (fp_line (start 3.898 -1.401) (end 3.898 -1)
      (stroke (width 0.15) (type solid)) (layer "F.SilkS"))
    (fp_line (start 3.898 14.098) (end 3.499 14.098)
      (stroke (width 0.15) (type solid)) (layer "F.SilkS"))
    (fp_line (start 3.898 14.098) (end 3.898 13.698)
      (stroke (width 0.15) (type solid)) (layer "F.SilkS"))
    (fp_line (start -1.52 -1.52) (end 4.04 -1.52)
      (stroke (width 0.05) (type solid)) (layer "F.CrtYd"))
    (fp_line (start -1.52 14.22) (end -1.52 -1.52)
      (stroke (width 0.05) (type solid)) (layer "F.CrtYd"))
    (fp_line (start -1.52 14.22) (end 4.04 14.22)
      (stroke (width 0.05) (type solid)) (layer "F.CrtYd"))
    (fp_line (start 4.04 14.22) (end 4.04 -1.52)
      (stroke (width 0.05) (type solid)) (layer "F.CrtYd"))
    (fp_line (start -1.27 -1.27) (end -1.27 13.97)
      (stroke (width 0.15) (type solid)) (layer "F.Fab"))
    (fp_line (start -1.27 -1.27) (end 3.809 -1.27)
      (stroke (width 0.15) (type solid)) (layer "F.Fab"))
    (fp_line (start -1.27 13.97) (end 3.809 13.97)
      (stroke (width 0.15) (type solid)) (layer "F.Fab"))
    (fp_line (start 3.809 -1.27) (end 3.809 13.97)
      (stroke (width 0.15) (type solid)) (layer "F.Fab"))
    (pad "1" thru_hole circle (at 0 0 90) (size 1.8 1.8) (drill 1.02) (layers "*.Cu" "*.Mask")
      (net 53 "SPI0_CS_N") (pintype "passive"))
    (pad "2" thru_hole circle (at 0 2.539 90) (size 1.8 1.8) (drill 1.02) (layers "*.Cu" "*.Mask")
      (net 55 "SPI0_MOSI") (pintype "passive"))
    (pad "3" thru_hole circle (at 0 5.078 90) (size 1.8 1.8) (drill 1.02) (layers "*.Cu" "*.Mask")
      (net 56 "SPI0_MISO") (pintype "passive"))
    (pad "4" thru_hole circle (at 0 7.618 90) (size 1.8 1.8) (drill 1.02) (layers "*.Cu" "*.Mask")
      (net 54 "SPI0_CLK") (pintype "passive"))
    (pad "5" thru_hole circle (at 0 10.159 90) (size 1.8 1.8) (drill 1.02) (layers "*.Cu" "*.Mask")
      (net 1 "GND") (pintype "passive"))
    (pad "6" thru_hole circle (at 0 12.698 90) (size 1.8 1.8) (drill 1.02) (layers "*.Cu" "*.Mask")
      (net 2 "VCC3V3") (pintype "passive"))
    (pad "7" thru_hole circle (at 2.539 0 90) (size 1.8 1.8) (drill 1.02) (layers "*.Cu" "*.Mask")
      (net 410 "PIRQ#") (pintype "passive"))
    (pad "8" thru_hole circle (at 2.539 2.539 90) (size 1.8 1.8) (drill 1.02) (layers "*.Cu" "*.Mask")
      (net 411 "RST") (pintype "passive"))
    (pad "9" thru_hole circle (at 2.539 5.078 90) (size 1.8 1.8) (drill 1.02) (layers "*.Cu" "*.Mask")
      (net 412 "GPIO") (pintype "passive"))
    (pad "10" thru_hole circle (at 2.539 7.618 90) (size 1.8 1.8) (drill 1.02) (layers "*.Cu" "*.Mask")
      (net 413 "PP") (pintype "passive"))
    (pad "11" thru_hole circle (at 2.539 10.159 90) (size 1.8 1.8) (drill 1.02) (layers "*.Cu" "*.Mask")
      (net 1 "GND") (pintype "passive"))
    (pad "12" thru_hole circle (at 2.539 12.698 90) (size 1.8 1.8) (drill 1.02) (layers "*.Cu" "*.Mask")
      (net 2 "VCC3V3") (pintype "passive"))
  )
	(footprint "antmicro-footprints:PinHeader_2x7_P2mm_Drill1mm_Shrouded" (layer "F.Cu")
    (at 142.64 68.565 180)
    (property "Author" "Antmicro")
    (property "License" "Apache-2.0")
    (property "MPN" "0878311420")
    (property "Manufacturer" "Molex")
    (property "Sheetfile" "interfaces.kicad_sch")
    (property "Sheetname" "Interfaces")
    (property "ki_description" "Pin Header, Wire-to-Board, 2 mm, 2 Rows, 14 Contacts, Surface Mount Straight, Milli-Grid 87832")
    (property "ki_keywords" "PINSTRIP, HEADER ")
    (attr through_hole)
    (fp_text reference "J9" (at -2.06 -5.45) (layer "F.SilkS")
        (effects (font (size 0.7 0.7) (thickness 0.15)) (justify right bottom))
    )
    (fp_text value "PinHeader_2x7_P2mm_Drill1mm_Shrouded" (at 0 3.4) (layer "F.Fab")
        (effects (font (size 0.7 0.7) (thickness 0.15)) (justify right bottom))
    )
    (fp_text user "License: Apache-2.0" (at -14.7 7.9) (layer "F.Fab") hide
        (effects (font (size 0.7 0.7) (thickness 0.15)) (justify right bottom))
    )
    (fp_text user "Author: Antmicro" (at -14.7 9.2) (layer "F.Fab") hide
        (effects (font (size 0.7 0.7) (thickness 0.15)) (justify right bottom))
    )
    (fp_text user "${REFERENCE}" (at -14.7 6.7) (layer "F.Fab") hide
        (effects (font (size 0.7 0.7) (thickness 0.15)) (justify right bottom))
    )
    (fp_line (start -2.41 2.2) (end 4.7 2.2)
      (stroke (width 0.15) (type solid)) (layer "F.SilkS"))
    (fp_line (start -2.4 -4.2) (end 14.4 -4.2)
      (stroke (width 0.15) (type solid)) (layer "F.SilkS"))
    (fp_line (start -2.4 2.2) (end -2.4 -4.2)
      (stroke (width 0.15) (type solid)) (layer "F.SilkS"))
    (fp_line (start 14.4 -4.2) (end 14.4 2.2)
      (stroke (width 0.15) (type solid)) (layer "F.SilkS"))
    (fp_line (start 14.4 2.2) (end 7.3 2.2)
      (stroke (width 0.15) (type solid)) (layer "F.SilkS"))
    (fp_line (start -2.51 -4.34) (end 14.51 -4.34)
      (stroke (width 0.05) (type solid)) (layer "F.CrtYd"))
    (fp_line (start -2.51 2.34) (end -2.51 -4.34)
      (stroke (width 0.05) (type solid)) (layer "F.CrtYd"))
    (fp_line (start -2.51 2.34) (end 14.51 2.34)
      (stroke (width 0.05) (type solid)) (layer "F.CrtYd"))
    (fp_line (start 14.51 2.34) (end 14.51 -4.34)
      (stroke (width 0.05) (type solid)) (layer "F.CrtYd"))
    (fp_line (start -2.33 2.15) (end -2.33 -4.13)
      (stroke (width 0.15) (type solid)) (layer "F.Fab"))
    (fp_line (start 14.356 -4.15) (end -2.32 -4.15)
      (stroke (width 0.15) (type solid)) (layer "F.Fab"))
    (fp_line (start 14.356 1.898) (end 14.356 -4.15)
      (stroke (width 0.15) (type solid)) (layer "F.Fab"))
    (fp_line (start 14.356 2.15) (end -2.293 2.15)
      (stroke (width 0.15) (type solid)) (layer "F.Fab"))
    (pad "1" thru_hole rect (at 0 0) (size 1.75 1.75) (drill 1) (layers "*.Cu" "*.Mask")
      (net 1 "GND") (pintype "passive"))
    (pad "2" thru_hole circle (at 0 -1.999) (size 1.75 1.75) (drill 1) (layers "*.Cu" "*.Mask")
      (net 2 "VCC3V3") (pintype "passive"))
    (pad "3" thru_hole circle (at 2 0) (size 1.75 1.75) (drill 1) (layers "*.Cu" "*.Mask")
      (net 1 "GND") (pintype "passive"))
    (pad "4" thru_hole circle (at 2 -1.999) (size 1.75 1.75) (drill 1) (layers "*.Cu" "*.Mask")
      (net 22 "JTAG_TMS") (pintype "passive"))
    (pad "5" thru_hole circle (at 4 0) (size 1.75 1.75) (drill 1) (layers "*.Cu" "*.Mask")
      (net 1 "GND") (pintype "passive"))
    (pad "6" thru_hole circle (at 4 -1.999) (size 1.75 1.75) (drill 1) (layers "*.Cu" "*.Mask")
      (net 21 "JTAG_TCK") (pintype "passive"))
    (pad "7" thru_hole circle (at 6 0) (size 1.75 1.75) (drill 1) (layers "*.Cu" "*.Mask")
      (net 1 "GND") (pintype "passive"))
    (pad "8" thru_hole circle (at 6 -1.999) (size 1.75 1.75) (drill 1) (layers "*.Cu" "*.Mask")
      (net 20 "JTAG_TDO") (pintype "passive"))
    (pad "9" thru_hole circle (at 8 0) (size 1.75 1.75) (drill 1) (layers "*.Cu" "*.Mask")
      (net 1 "GND") (pintype "passive"))
    (pad "10" thru_hole circle (at 8 -1.999) (size 1.75 1.75) (drill 1) (layers "*.Cu" "*.Mask")
      (net 19 "JTAG_TDI") (pintype "passive"))
    (pad "11" thru_hole circle (at 10 0) (size 1.75 1.75) (drill 1) (layers "*.Cu" "*.Mask")
      (net 1 "GND") (pintype "passive"))
    (pad "12" thru_hole circle (at 10 -1.999) (size 1.75 1.75) (drill 1) (layers "*.Cu" "*.Mask")
      (net 425 "unconnected-(J9-Pad12)") (pintype "passive+no_connect"))
    (pad "13" thru_hole circle (at 12 0) (size 1.75 1.75) (drill 1) (layers "*.Cu" "*.Mask")
      (net 1 "GND") (pintype "passive"))
    (pad "14" thru_hole circle (at 12 -1.999) (size 1.75 1.75) (drill 1) (layers "*.Cu" "*.Mask")
      (net 426 "unconnected-(J9-Pad14)") (pintype "passive+no_connect"))
  )
	(footprint "antmicro-footprints:Spacer_Drill3.7mm_H4mm_9774040151R" (layer "F.Cu")
    (at 73.811 112.426)
    (descr "Spacer steel M2.5 h=4mm fi=5.1mm")
    (property "Author" "Antmicro")
    (property "License" "Apache-2.0")
    (property "MPN" "9774040151R")
    (property "Manufacturer" "Würth Elektronik")
    (property "Public" "False")
    (property "Sheetfile" "rot.kicad_sch")
    (property "Sheetname" "RoT")
    (property "ki_description" "Round Standoff Threaded M2.5x0.45 Steel 0.157\" (4.00mm)")
    (property "ki_keywords" "SPACER")
    (attr smd)
    (fp_text reference "H2" (at 0 -3.15) (layer "F.SilkS")
        (effects (font (size 0.7 0.7) (thickness 0.15)) (justify left bottom))
    )
    (fp_text value "Spacer_Drill3.7mm_H4mm_9774040151R" (at 0 3.95) (layer "F.Fab")
        (effects (font (size 0.7 0.7) (thickness 0.15)) (justify left bottom))
    )
    (fp_text user "${REFERENCE}" (at -2.551 6.349) (layer "F.Fab") hide
        (effects (font (size 0.7 0.7) (thickness 0.15)) (justify left bottom))
    )
    (fp_text user "License: Apache-2.0" (at -2.551 8.749) (layer "F.Fab") hide
        (effects (font (size 0.7 0.7) (thickness 0.15)) (justify left bottom))
    )
    (fp_text user "Author: Antmicro" (at -2.551 7.549) (layer "F.Fab") hide
        (effects (font (size 0.7 0.7) (thickness 0.15)) (justify left bottom))
    )
    (fp_circle (center 0 0) (end 3.05 0)
      (stroke (width 0.05) (type solid)) (fill none) (layer "F.CrtYd"))
    (pad "" smd custom (at -1.7 -1.71) (size 0.62 0.62) (layers "F.Paste")
      (thermal_bridge_angle 90)
      (options (clearance outline) (anchor circle))
      (primitives
        (gr_arc (start -0.250195 1.279127) (mid 0.285453 0.294389) (end 1.266786 -0.24747) (width 0.2))
        (gr_arc (start -0.34334 1.279127) (mid 0.218448 0.232561) (end 1.259603 -0.339191) (width 0.2))
        (gr_arc (start -0.436309 1.279127) (mid 0.152481 0.169693) (end 1.255279 -0.431435) (width 0.2))
        (gr_arc (start -0.529126 1.279127) (mid 0.087542 0.105784) (end 1.253811 -0.524161) (width 0.2))
        (gr_arc (start -0.621807 1.279127) (mid 0.0309 0.033527) (end 1.275473 -0.621136) (width 0.2))
        (gr_arc (start -0.71437 1.279127) (mid -0.037758 -0.026651) (end 1.263664 -0.711602) (width 0.2))
        (gr_arc (start -0.806826 1.279127) (mid -0.105837 -0.087395) (end 1.253435 -0.802342) (width 0.2))
        (gr_arc (start -0.899187 1.279127) (mid -0.165236 -0.156885) (end 1.267475 -0.897258) (width 0.2))
        (gr_arc (start -0.991463 1.279127) (mid -0.228522 -0.222449) (end 1.270645 -0.990112) (width 0.2))
        (gr_arc (start -1.083663 1.279127) (mid -0.294507 -0.285313) (end 1.266278 -1.081674) (width 0.2))
        (gr_line (start 1.279127 -0.250195) (end 1.279127 -1.083663) (width 0.2))
        (gr_line (start -0.250195 1.279127) (end -1.083663 1.279127) (width 0.2))
      ))
    (pad "" smd custom (at -1.7 1.699 90) (size 0.62 0.62) (layers "F.Paste")
      (thermal_bridge_angle 90)
      (options (clearance outline) (anchor circle))
      (primitives
        (gr_arc (start -0.250195 1.279127) (mid 0.285453 0.294389) (end 1.266786 -0.24747) (width 0.2))
        (gr_arc (start -0.34334 1.279127) (mid 0.218448 0.232561) (end 1.259603 -0.339191) (width 0.2))
        (gr_arc (start -0.436309 1.279127) (mid 0.152481 0.169693) (end 1.255279 -0.431435) (width 0.2))
        (gr_arc (start -0.529126 1.279127) (mid 0.087542 0.105784) (end 1.253811 -0.524161) (width 0.2))
        (gr_arc (start -0.621807 1.279127) (mid 0.0309 0.033527) (end 1.275473 -0.621136) (width 0.2))
        (gr_arc (start -0.71437 1.279127) (mid -0.037758 -0.026651) (end 1.263664 -0.711602) (width 0.2))
        (gr_arc (start -0.806826 1.279127) (mid -0.105837 -0.087395) (end 1.253435 -0.802342) (width 0.2))
        (gr_arc (start -0.899187 1.279127) (mid -0.165236 -0.156885) (end 1.267475 -0.897258) (width 0.2))
        (gr_arc (start -0.991463 1.279127) (mid -0.228522 -0.222449) (end 1.270645 -0.990112) (width 0.2))
        (gr_arc (start -1.083663 1.279127) (mid -0.294507 -0.285313) (end 1.266278 -1.081674) (width 0.2))
        (gr_line (start 1.279127 -0.250195) (end 1.279127 -1.083663) (width 0.2))
        (gr_line (start -0.250195 1.279127) (end -1.083663 1.279127) (width 0.2))
      ))
    (pad "" smd custom (at 1.709 -1.71 270) (size 0.62 0.62) (layers "F.Paste")
      (thermal_bridge_angle 90)
      (options (clearance outline) (anchor circle))
      (primitives
        (gr_arc (start -0.250195 1.279127) (mid 0.285453 0.294389) (end 1.266786 -0.24747) (width 0.2))
        (gr_arc (start -0.34334 1.279127) (mid 0.218448 0.232561) (end 1.259603 -0.339191) (width 0.2))
        (gr_arc (start -0.436309 1.279127) (mid 0.152481 0.169693) (end 1.255279 -0.431435) (width 0.2))
        (gr_arc (start -0.529126 1.279127) (mid 0.087542 0.105784) (end 1.253811 -0.524161) (width 0.2))
        (gr_arc (start -0.621807 1.279127) (mid 0.0309 0.033527) (end 1.275473 -0.621136) (width 0.2))
        (gr_arc (start -0.71437 1.279127) (mid -0.037758 -0.026651) (end 1.263664 -0.711602) (width 0.2))
        (gr_arc (start -0.806826 1.279127) (mid -0.105837 -0.087395) (end 1.253435 -0.802342) (width 0.2))
        (gr_arc (start -0.899187 1.279127) (mid -0.165236 -0.156885) (end 1.267475 -0.897258) (width 0.2))
        (gr_arc (start -0.991463 1.279127) (mid -0.228522 -0.222449) (end 1.270645 -0.990112) (width 0.2))
        (gr_arc (start -1.083663 1.279127) (mid -0.294507 -0.285313) (end 1.266278 -1.081674) (width 0.2))
        (gr_line (start 1.279127 -0.250195) (end 1.279127 -1.083663) (width 0.2))
        (gr_line (start -0.250195 1.279127) (end -1.083663 1.279127) (width 0.2))
      ))
    (pad "" smd custom (at 1.709 1.699 180) (size 0.62 0.62) (layers "F.Paste")
      (thermal_bridge_angle 90)
      (options (clearance outline) (anchor circle))
      (primitives
        (gr_arc (start -0.250195 1.279127) (mid 0.285453 0.294389) (end 1.266786 -0.24747) (width 0.2))
        (gr_arc (start -0.34334 1.279127) (mid 0.218448 0.232561) (end 1.259603 -0.339191) (width 0.2))
        (gr_arc (start -0.436309 1.279127) (mid 0.152481 0.169693) (end 1.255279 -0.431435) (width 0.2))
        (gr_arc (start -0.529126 1.279127) (mid 0.087542 0.105784) (end 1.253811 -0.524161) (width 0.2))
        (gr_arc (start -0.621807 1.279127) (mid 0.0309 0.033527) (end 1.275473 -0.621136) (width 0.2))
        (gr_arc (start -0.71437 1.279127) (mid -0.037758 -0.026651) (end 1.263664 -0.711602) (width 0.2))
        (gr_arc (start -0.806826 1.279127) (mid -0.105837 -0.087395) (end 1.253435 -0.802342) (width 0.2))
        (gr_arc (start -0.899187 1.279127) (mid -0.165236 -0.156885) (end 1.267475 -0.897258) (width 0.2))
        (gr_arc (start -0.991463 1.279127) (mid -0.228522 -0.222449) (end 1.270645 -0.990112) (width 0.2))
        (gr_arc (start -1.083663 1.279127) (mid -0.294507 -0.285313) (end 1.266278 -1.081674) (width 0.2))
        (gr_line (start 1.279127 -0.250195) (end 1.279127 -1.083663) (width 0.2))
        (gr_line (start -0.250195 1.279127) (end -1.083663 1.279127) (width 0.2))
      ))
    (pad "1" thru_hole circle (at 0 0) (size 6 6) (drill 3.7) (layers "*.Cu" "*.Mask")
      (net 779 "unconnected-(H2-Pad1)") (pintype "passive+no_connect") (solder_paste_margin_ratio -0.05))
  )
)
